(kicad_pcb
	(version 20260206)
	(generator "pcbnew")
	(generator_version "10.0")
	(general
		(thickness 1.6)
		(legacy_teardrops no)
	)
	(paper "A4")
	(title_block
		(title "01162023_DA0F0TEBIF0_F0T_Expander_BD_F_brd_V02_OCP.brd")
		(comment 1 "Grand Teton / footprints 48-52 of 9728")
	)
	(layers
		(0 "F.Cu" signal "TOP")
		(4 "In1.Cu" signal "GND")
		(6 "In2.Cu" signal "VCC")
		(8 "In3.Cu" signal "VCC1")
		(10 "In4.Cu" signal "GND1")
		(12 "In5.Cu" signal "IN1")
		(14 "In6.Cu" signal "GND2")
		(16 "In7.Cu" signal "IN2")
		(18 "In8.Cu" signal "GND3")
		(20 "In9.Cu" signal "IN3")
		(22 "In10.Cu" signal "GND4")
		(24 "In11.Cu" signal "IN4")
		(26 "In12.Cu" signal "GND5")
		(28 "In13.Cu" signal "IN5")
		(30 "In14.Cu" signal "GND6")
		(32 "In15.Cu" signal "IN6")
		(34 "In16.Cu" signal "GND7")
		(2 "B.Cu" signal "BOTTOM")
		(9 "F.Adhes" user "F.Adhesive")
		(11 "B.Adhes" user "B.Adhesive")
		(13 "F.Paste" user "Package Geometry/Pastemask Top")
		(15 "B.Paste" user "Package Geometry/Pastemask Bottom")
		(5 "F.SilkS" user "Ref Des/Silkscreen Top")
		(7 "B.SilkS" user "Ref Des/Silkscreen Bottom")
		(1 "F.Mask" user "Board Geometry/Soldermask Top")
		(3 "B.Mask" user "Board Geometry/Soldermask Bottom")
		(17 "Dwgs.User" user "User.Drawings")
		(19 "Cmts.User" user "User.Comments")
		(21 "Eco1.User" user "User.Eco1")
		(23 "Eco2.User" user "User.Eco2")
		(25 "Edge.Cuts" user "Board Geometry/Outline")
		(27 "Margin" user)
		(31 "F.CrtYd" user "Package Geometry/Place Bound Top")
		(29 "B.CrtYd" user "Package Geometry/Place Bound Bottom")
		(35 "F.Fab" user "Ref Des/Assembly Top")
		(33 "B.Fab" user "Ref Des/Assembly Bottom")
	)
	(footprint ""
		(layer "F.Cu")
		(at 377.910344 18.028412 180)
		(property "Reference" "DE04F_1"
			(at 2.472944 3.066542 0)
			(unlocked yes)
			(layer "F.SilkS")
			(effects
				(font
					(size 0.7874 0.5842)
					(thickness 0.1524)
				)
				(justify left)
			)
		)
		(property "Value" ""
			(at 0 0 180)
			(layer "F.Fab")
			(effects
				(font
					(size 1.27 1.27)
				)
			)
		)
		(duplicate_pad_numbers_are_jumpers no)
		(fp_line
			(start 1.2192 2.1082)
			(end -1.2192 2.1082)
			(stroke
				(width 0.1524)
				(type default)
			)
			(layer "F.SilkS")
		)
		(fp_line
			(start 1.2192 -2.1082)
			(end 1.2192 2.1082)
			(stroke
				(width 0.1524)
				(type default)
			)
			(layer "F.SilkS")
		)
		(fp_line
			(start -1.2192 2.1082)
			(end -1.2192 -2.1082)
			(stroke
				(width 0.1524)
				(type default)
			)
			(layer "F.SilkS")
		)
		(fp_line
			(start -1.2192 -2.1082)
			(end 1.2192 -2.1082)
			(stroke
				(width 0.1524)
				(type default)
			)
			(layer "F.SilkS")
		)
		(pad "" np_thru_hole circle
			(at -2.8829 -1.27 90)
			(size 1.0414 1.0414)
			(drill 1.0414)
			(layers "*.Cu" "*.Mask")
			(clearance 0.381)
			(thermal_gap 0.381)
		)
		(pad "" np_thru_hole circle
			(at -2.8829 1.27 90)
			(size 1.0414 1.0414)
			(drill 1.0414)
			(layers "*.Cu" "*.Mask")
			(clearance 0.381)
			(thermal_gap 0.381)
		)
		(pad "" np_thru_hole circle
			(at 3.4671 -1.27 90)
			(size 1.0414 1.0414)
			(drill 1.0414)
			(layers "*.Cu" "*.Mask")
			(clearance 0.381)
			(thermal_gap 0.381)
		)
		(pad "" np_thru_hole circle
			(at 3.4671 1.27 90)
			(size 1.0414 1.0414)
			(drill 1.0414)
			(layers "*.Cu" "*.Mask")
			(clearance 0.381)
			(thermal_gap 0.381)
		)
		(pad "1" smd rect
			(at 0.8255 -0.249936 90)
			(size 0.3048 0.508)
			(layers "F.Cu" "F.Mask" "F.Paste")
			(net "85_5INCH_IN2_DN")
		)
		(pad "2" smd rect
			(at 0.8255 0.249936 90)
			(size 0.3048 0.508)
			(layers "F.Cu" "F.Mask" "F.Paste")
			(net "85_5INCH_IN2_DP")
		)
		(pad "3" smd circle
			(at 0 0 180)
			(size 0 0)
			(layers "F.Cu" "F.Mask" "F.Paste")
			(net "COUPON_GND2")
		)
		(zone
			(layer "F.Cu")
			(hatch none 0.5)
			(connect_pads
				(clearance 0)
			)
			(min_thickness 0.25)
			(keepout
				(tracks not_allowed)
				(vias allowed)
				(pads allowed)
				(copperpour not_allowed)
				(footprints allowed)
			)
			(placement
				(enabled no)
				(sheetname "")
			)
			(fill
				(thermal_gap 0.5)
				(thermal_bridge_width 0.5)
				(island_removal_mode 0)
			)
			(polygon
				(pts
					(xy 376.792744 18.577052) (xy 376.792744 18.481548) (xy 377.389644 18.481548) (xy 377.389644 18.075148)
					(xy 376.792744 18.075148) (xy 376.792744 17.981676) (xy 377.389644 17.981676) (xy 377.389644 17.575276)
					(xy 376.792744 17.575276) (xy 376.792744 17.479772) (xy 377.491244 17.479772) (xy 377.491244 18.577052)
				)
			)
		)
		(zone
			(layers "F.Cu" "B.Cu" "In1.Cu" "In2.Cu" "In3.Cu" "In4.Cu" "In5.Cu" "In6.Cu"
				"In7.Cu" "In8.Cu" "In9.Cu" "In10.Cu" "In11.Cu" "In12.Cu" "In13.Cu" "In14.Cu"
				"In15.Cu" "In16.Cu"
			)
			(hatch none 0.5)
			(connect_pads
				(clearance 0)
			)
			(min_thickness 0.25)
			(keepout
				(tracks not_allowed)
				(vias allowed)
				(pads allowed)
				(copperpour not_allowed)
				(footprints allowed)
			)
			(placement
				(enabled no)
				(sheetname "")
			)
			(fill
				(thermal_gap 0.5)
				(thermal_bridge_width 0.5)
				(island_removal_mode 0)
			)
			(polygon
				(pts
					(arc
						(start 375.370344 16.758412)
						(mid 373.516144 16.758412)
						(end 375.370344 16.758412)
					)
				)
			)
		)
		(zone
			(layers "F.Cu" "B.Cu" "In1.Cu" "In2.Cu" "In3.Cu" "In4.Cu" "In5.Cu" "In6.Cu"
				"In7.Cu" "In8.Cu" "In9.Cu" "In10.Cu" "In11.Cu" "In12.Cu" "In13.Cu" "In14.Cu"
				"In15.Cu" "In16.Cu"
			)
			(hatch none 0.5)
			(connect_pads
				(clearance 0)
			)
			(min_thickness 0.25)
			(keepout
				(tracks not_allowed)
				(vias allowed)
				(pads allowed)
				(copperpour not_allowed)
				(footprints allowed)
			)
			(placement
				(enabled no)
				(sheetname "")
			)
			(fill
				(thermal_gap 0.5)
				(thermal_bridge_width 0.5)
				(island_removal_mode 0)
			)
			(polygon
				(pts
					(arc
						(start 375.370344 19.298412)
						(mid 373.516144 19.298412)
						(end 375.370344 19.298412)
					)
				)
			)
		)
		(zone
			(layers "F.Cu" "B.Cu" "In1.Cu" "In2.Cu" "In3.Cu" "In4.Cu" "In5.Cu" "In6.Cu"
				"In7.Cu" "In8.Cu" "In9.Cu" "In10.Cu" "In11.Cu" "In12.Cu" "In13.Cu" "In14.Cu"
				"In15.Cu" "In16.Cu"
			)
			(hatch none 0.5)
			(connect_pads
				(clearance 0)
			)
			(min_thickness 0.25)
			(keepout
				(tracks not_allowed)
				(vias allowed)
				(pads allowed)
				(copperpour not_allowed)
				(footprints allowed)
			)
			(placement
				(enabled no)
				(sheetname "")
			)
			(fill
				(thermal_gap 0.5)
				(thermal_bridge_width 0.5)
				(island_removal_mode 0)
			)
			(polygon
				(pts
					(arc
						(start 381.720344 16.758412)
						(mid 379.866144 16.758412)
						(end 381.720344 16.758412)
					)
				)
			)
		)
		(zone
			(layers "F.Cu" "B.Cu" "In1.Cu" "In2.Cu" "In3.Cu" "In4.Cu" "In5.Cu" "In6.Cu"
				"In7.Cu" "In8.Cu" "In9.Cu" "In10.Cu" "In11.Cu" "In12.Cu" "In13.Cu" "In14.Cu"
				"In15.Cu" "In16.Cu"
			)
			(hatch none 0.5)
			(connect_pads
				(clearance 0)
			)
			(min_thickness 0.25)
			(keepout
				(tracks not_allowed)
				(vias allowed)
				(pads allowed)
				(copperpour not_allowed)
				(footprints allowed)
			)
			(placement
				(enabled no)
				(sheetname "")
			)
			(fill
				(thermal_gap 0.5)
				(thermal_bridge_width 0.5)
				(island_removal_mode 0)
			)
			(polygon
				(pts
					(arc
						(start 381.720344 19.298412)
						(mid 379.866144 19.298412)
						(end 381.720344 19.298412)
					)
				)
			)
		)
	)
	(footprint ""
		(layer "F.Cu")
		(at 456.964288 -318.772032 -90)
		(property "Reference" "PL23"
			(at 0 0 270)
			(layer "F.SilkS")
			(hide yes)
			(effects
				(font
					(size 1.27 1.27)
				)
			)
		)
		(property "Value" ""
			(at 0 0 270)
			(layer "F.Fab")
			(effects
				(font
					(size 1.27 1.27)
				)
			)
		)
		(duplicate_pad_numbers_are_jumpers no)
		(fp_line
			(start -1.27 0.5842)
			(end -1.27 -0.5842)
			(stroke
				(width 0.1524)
				(type default)
			)
			(layer "F.SilkS")
		)
		(fp_line
			(start 1.27 0.5842)
			(end -1.27 0.5842)
			(stroke
				(width 0.1524)
				(type default)
			)
			(layer "F.SilkS")
		)
		(fp_line
			(start 1.27 0.5842)
			(end 1.27 -0.5842)
			(stroke
				(width 0.1524)
				(type default)
			)
			(layer "F.SilkS")
		)
		(fp_line
			(start -1.27 -0.5588)
			(end -1.27 -0.5842)
			(stroke
				(width 0.1524)
				(type default)
			)
			(layer "F.SilkS")
		)
		(fp_line
			(start -1.27 -0.5842)
			(end 1.27 -0.5842)
			(stroke
				(width 0.1524)
				(type default)
			)
			(layer "F.SilkS")
		)
		(fp_line
			(start -0.9144 0.508)
			(end -0.9144 0.406654)
			(stroke
				(width 0.1)
				(type default)
			)
			(layer "F.Fab")
		)
		(fp_line
			(start 0.9144 0.508)
			(end -0.9144 0.508)
			(stroke
				(width 0.1)
				(type default)
			)
			(layer "F.Fab")
		)
		(fp_line
			(start -1.194308 0.406654)
			(end -1.194308 -0.406654)
			(stroke
				(width 0.1)
				(type default)
			)
			(layer "F.Fab")
		)
		(fp_line
			(start -0.9144 0.406654)
			(end -1.194308 0.406654)
			(stroke
				(width 0.1)
				(type default)
			)
			(layer "F.Fab")
		)
		(fp_line
			(start 0.9144 0.4064)
			(end 0.9144 0.508)
			(stroke
				(width 0.1)
				(type default)
			)
			(layer "F.Fab")
		)
		(fp_line
			(start 1.1938 0.4064)
			(end 0.9144 0.4064)
			(stroke
				(width 0.1)
				(type default)
			)
			(layer "F.Fab")
		)
		(fp_line
			(start -1.194308 -0.406654)
			(end -0.9144 -0.406654)
			(stroke
				(width 0.1)
				(type default)
			)
			(layer "F.Fab")
		)
		(fp_line
			(start -0.9144 -0.406654)
			(end -0.9144 -0.508)
			(stroke
				(width 0.1)
				(type default)
			)
			(layer "F.Fab")
		)
		(fp_line
			(start 0.9144 -0.406654)
			(end 1.1938 -0.406654)
			(stroke
				(width 0.1)
				(type default)
			)
			(layer "F.Fab")
		)
		(fp_line
			(start 1.1938 -0.406654)
			(end 1.1938 0.4064)
			(stroke
				(width 0.1)
				(type default)
			)
			(layer "F.Fab")
		)
		(fp_line
			(start -0.9144 -0.508)
			(end 0.9144 -0.508)
			(stroke
				(width 0.1)
				(type default)
			)
			(layer "F.Fab")
		)
		(fp_line
			(start 0.9144 -0.508)
			(end 0.9144 -0.406654)
			(stroke
				(width 0.1)
				(type default)
			)
			(layer "F.Fab")
		)
		(pad "1" smd rect
			(at -0.7366 0 180)
			(size 0.7112 0.8128)
			(layers "F.Cu" "F.Mask" "F.Paste")
			(net "P12V_AUX")
		)
		(pad "2" smd rect
			(at 0.7366 0 180)
			(size 0.7112 0.8128)
			(layers "F.Cu" "F.Mask" "F.Paste")
			(net "SW_P12V_P1V25_PEX3_FLT")
		)
	)
	(footprint ""
		(layer "F.Cu")
		(at 322.91909 -229.952296)
		(property "Reference" "Q113"
			(at -4.13893 -1.342898 0)
			(unlocked yes)
			(layer "F.SilkS")
			(effects
				(font
					(size 0.7874 0.5842)
					(thickness 0.1524)
				)
			)
		)
		(property "Value" ""
			(at 0 0 0)
			(layer "F.Fab")
			(effects
				(font
					(size 1.27 1.27)
				)
			)
		)
		(duplicate_pad_numbers_are_jumpers no)
		(fp_line
			(start -1.376172 -1.199896)
			(end -0.508 -1.199896)
			(stroke
				(width 0.1524)
				(type default)
			)
			(layer "F.SilkS")
		)
		(fp_line
			(start -1.376172 1.199896)
			(end -1.376172 -1.199896)
			(stroke
				(width 0.1524)
				(type default)
			)
			(layer "F.SilkS")
		)
		(fp_line
			(start -0.508 -1.199896)
			(end 0 -0.762)
			(stroke
				(width 0.1524)
				(type default)
			)
			(layer "F.SilkS")
		)
		(fp_line
			(start 0 -0.762)
			(end 0.508 -1.199896)
			(stroke
				(width 0.1524)
				(type default)
			)
			(layer "F.SilkS")
		)
		(fp_line
			(start 0.508 -1.199896)
			(end 1.376172 -1.199896)
			(stroke
				(width 0.1524)
				(type default)
			)
			(layer "F.SilkS")
		)
		(fp_line
			(start 1.376172 -1.199896)
			(end 1.376172 1.199896)
			(stroke
				(width 0.1524)
				(type default)
			)
			(layer "F.SilkS")
		)
		(fp_line
			(start 1.376172 1.199896)
			(end -1.376172 1.199896)
			(stroke
				(width 0.1524)
				(type default)
			)
			(layer "F.SilkS")
		)
		(fp_poly
			(pts
				(xy -1.350772 -1.041908) (xy -2.112772 -1.422908) (xy -2.112772 -0.660908)
			)
			(stroke
				(width 0)
				(type default)
			)
			(fill yes)
			(layer "F.SilkS")
		)
		(fp_line
			(start -0.674878 -1.100074)
			(end 0.674878 -1.100074)
			(stroke
				(width 0.1)
				(type default)
			)
			(layer "F.Fab")
		)
		(fp_line
			(start -0.674878 1.100074)
			(end -0.674878 -1.100074)
			(stroke
				(width 0.1)
				(type default)
			)
			(layer "F.Fab")
		)
		(fp_line
			(start 0.674878 -1.100074)
			(end 0.674878 1.100074)
			(stroke
				(width 0.1)
				(type default)
			)
			(layer "F.Fab")
		)
		(fp_line
			(start 0.674878 1.100074)
			(end -0.674878 1.100074)
			(stroke
				(width 0.1)
				(type default)
			)
			(layer "F.Fab")
		)
		(fp_poly
			(pts
				(xy -1.4605 -0.7493) (xy -2.2225 -1.1303) (xy -2.2225 -0.3683)
			)
			(stroke
				(width 0)
				(type default)
			)
			(fill yes)
			(layer "F.Fab")
		)
		(pad "1" smd rect
			(at -0.899922 -0.750062 270)
			(size 0.6096 0.6096)
			(layers "F.Cu" "F.Mask" "F.Paste")
			(net "GND")
		)
		(pad "2" smd rect
			(at -0.899922 0 270)
			(size 0.4064 0.6096)
			(layers "F.Cu" "F.Mask" "F.Paste")
			(net "FPGA_DEBUG_LED")
		)
		(pad "3" smd rect
			(at -0.899922 0.750062 270)
			(size 0.6096 0.6096)
			(layers "F.Cu" "F.Mask" "F.Paste")
			(net "Net_9082")
		)
		(pad "4" smd rect
			(at 0.899922 0.750062 270)
			(size 0.6096 0.6096)
			(layers "F.Cu" "F.Mask" "F.Paste")
			(net "Net_9080")
		)
		(pad "5" smd rect
			(at 0.899922 0 270)
			(size 0.4064 0.6096)
			(layers "F.Cu" "F.Mask" "F.Paste")
			(net "Net_9081")
		)
		(pad "6" smd rect
			(at 0.899922 -0.750062 270)
			(size 0.6096 0.6096)
			(layers "F.Cu" "F.Mask" "F.Paste")
			(net "FPGA_DEBUG_LED_N")
		)
	)
	(footprint ""
		(layer "F.Cu")
		(at 393.954762 -22.867366 90)
		(property "Reference" "C3969"
			(at 0 0 90)
			(layer "F.SilkS")
			(hide yes)
			(effects
				(font
					(size 1.27 1.27)
				)
			)
		)
		(property "Value" ""
			(at 0 0 90)
			(layer "F.Fab")
			(effects
				(font
					(size 1.27 1.27)
				)
			)
		)
		(duplicate_pad_numbers_are_jumpers no)
		(fp_line
			(start 0.7874 -0.4064)
			(end 0.7874 0.4064)
			(stroke
				(width 0.1524)
				(type default)
			)
			(layer "F.SilkS")
		)
		(fp_line
			(start -0.7874 -0.4064)
			(end 0.7874 -0.4064)
			(stroke
				(width 0.1524)
				(type default)
			)
			(layer "F.SilkS")
		)
		(fp_line
			(start 0.7874 0.4064)
			(end -0.7874 0.4064)
			(stroke
				(width 0.1524)
				(type default)
			)
			(layer "F.SilkS")
		)
		(fp_line
			(start -0.7874 0.4064)
			(end -0.7874 -0.4064)
			(stroke
				(width 0.1524)
				(type default)
			)
			(layer "F.SilkS")
		)
		(fp_line
			(start -0.12065 -0.305054)
			(end -0.12065 -0.2794)
			(stroke
				(width 0.1)
				(type default)
			)
			(layer "F.Fab")
		)
		(fp_line
			(start -0.67945 -0.305054)
			(end -0.12065 -0.305054)
			(stroke
				(width 0.1)
				(type default)
			)
			(layer "F.Fab")
		)
		(fp_line
			(start 0.67945 -0.3048)
			(end 0.67945 0.3048)
			(stroke
				(width 0.1)
				(type default)
			)
			(layer "F.Fab")
		)
		(fp_line
			(start 0.12065 -0.3048)
			(end 0.67945 -0.3048)
			(stroke
				(width 0.1)
				(type default)
			)
			(layer "F.Fab")
		)
		(fp_line
			(start 0.12065 -0.2794)
			(end 0.12065 -0.3048)
			(stroke
				(width 0.1)
				(type default)
			)
			(layer "F.Fab")
		)
		(fp_line
			(start -0.12065 -0.2794)
			(end 0.12065 -0.2794)
			(stroke
				(width 0.1)
				(type default)
			)
			(layer "F.Fab")
		)
		(fp_line
			(start 0.120396 0.2794)
			(end -0.12065 0.2794)
			(stroke
				(width 0.1)
				(type default)
			)
			(layer "F.Fab")
		)
		(fp_line
			(start -0.12065 0.2794)
			(end -0.12065 0.3048)
			(stroke
				(width 0.1)
				(type default)
			)
			(layer "F.Fab")
		)
		(fp_line
			(start 0.67945 0.3048)
			(end 0.120396 0.3048)
			(stroke
				(width 0.1)
				(type default)
			)
			(layer "F.Fab")
		)
		(fp_line
			(start 0.120396 0.3048)
			(end 0.120396 0.2794)
			(stroke
				(width 0.1)
				(type default)
			)
			(layer "F.Fab")
		)
		(fp_line
			(start -0.12065 0.3048)
			(end -0.67945 0.3048)
			(stroke
				(width 0.1)
				(type default)
			)
			(layer "F.Fab")
		)
		(fp_line
			(start -0.67945 0.3048)
			(end -0.67945 -0.305054)
			(stroke
				(width 0.1)
				(type default)
			)
			(layer "F.Fab")
		)
		(pad "1" smd circle
			(at -0.40005 0 90)
			(size 0 0)
			(layers "F.Cu" "F.Mask" "F.Paste")
			(net "P12V_SSD13")
		)
		(pad "2" smd circle
			(at 0.40005 0 90)
			(size 0 0)
			(layers "F.Cu" "F.Mask" "F.Paste")
			(net "GND")
		)
	)
	(footprint ""
		(layer "F.Cu")
		(at 69.792342 -28.225242 180)
		(property "Reference" "C88"
			(at 0 0 180)
			(layer "F.SilkS")
			(hide yes)
			(effects
				(font
					(size 1.27 1.27)
				)
			)
		)
		(property "Value" ""
			(at 0 0 180)
			(layer "F.Fab")
			(effects
				(font
					(size 1.27 1.27)
				)
			)
		)
		(duplicate_pad_numbers_are_jumpers no)
		(fp_line
			(start 0.299974 0.150114)
			(end -0.299974 0.150114)
			(stroke
				(width 0.1)
				(type default)
			)
			(layer "F.Fab")
		)
		(fp_line
			(start 0.299974 -0.150114)
			(end 0.299974 0.150114)
			(stroke
				(width 0.1)
				(type default)
			)
			(layer "F.Fab")
		)
		(fp_line
			(start -0.299974 0.150114)
			(end -0.299974 -0.150114)
			(stroke
				(width 0.1)
				(type default)
			)
			(layer "F.Fab")
		)
		(fp_line
			(start -0.299974 -0.150114)
			(end 0.299974 -0.150114)
			(stroke
				(width 0.1)
				(type default)
			)
			(layer "F.Fab")
		)
		(pad "1" smd rect
			(at -0.2667 0 180)
			(size 0.3048 0.381)
			(layers "F.Cu" "F.Mask" "F.Paste")
			(net "P5E_PEX0_STN2_TX_DN<36>")
		)
		(pad "2" smd rect
			(at 0.2667 0 180)
			(size 0.3048 0.381)
			(layers "F.Cu" "F.Mask" "F.Paste")
			(net "P5E_PEX0_STN2_TX_C_DN<36>")
		)
	)
)
